(kicad_pcb
	(version 20260206)
	(generator "pcbnew")
	(generator_version "10.0")
	(general
		(thickness 1.6)
		(legacy_teardrops no)
	)
	(paper "A4")
	(title_block
		(title "v2-pdb — ms_pdb_v2.brd")
		(comment 1 "Open CloudServer (Microsoft) / footprints 24-33 of 348")
	)
	(layers
		(0 "F.Cu" signal "TOP")
		(4 "In1.Cu" signal "GND")
		(6 "In2.Cu" signal "IN1")
		(8 "In3.Cu" signal "VCC")
		(10 "In4.Cu" signal "VCC1")
		(12 "In5.Cu" signal "IN2")
		(14 "In6.Cu" signal "GND1")
		(2 "B.Cu" signal "BOTTOM")
		(9 "F.Adhes" user "F.Adhesive")
		(11 "B.Adhes" user "B.Adhesive")
		(13 "F.Paste" user "Package Geometry/Pastemask Top")
		(15 "B.Paste" user "Package Geometry/Pastemask Bottom")
		(5 "F.SilkS" user "Ref Des/Silkscreen Top")
		(7 "B.SilkS" user "Ref Des/Silkscreen Bottom")
		(1 "F.Mask" user "Board Geometry/Soldermask Top")
		(3 "B.Mask" user "Board Geometry/Soldermask Bottom")
		(17 "Dwgs.User" user "User.Drawings")
		(19 "Cmts.User" user "User.Comments")
		(21 "Eco1.User" user "User.Eco1")
		(23 "Eco2.User" user "User.Eco2")
		(25 "Edge.Cuts" user "Board Geometry/Outline")
		(27 "Margin" user)
		(31 "F.CrtYd" user "Package Geometry/Place Bound Top")
		(29 "B.CrtYd" user "Package Geometry/Place Bound Bottom")
		(35 "F.Fab" user "Ref Des/Assembly Top")
		(33 "B.Fab" user "Ref Des/Assembly Bottom")
	)
	(footprint ""
		(layer "F.Cu")
		(at 25.997662 -9.509252)
		(property "Reference" "R63"
			(at -3.764788 0.113792 0)
			(unlocked yes)
			(layer "F.SilkS")
			(effects
				(font
					(size 0.7874 0.5842)
					(thickness 0.1524)
				)
				(justify left)
			)
		)
		(property "Value" ""
			(at 0 0 0)
			(layer "F.Fab")
			(effects
				(font
					(size 1.27 1.27)
				)
			)
		)
		(duplicate_pad_numbers_are_jumpers no)
		(fp_line
			(start -0.7874 -0.4064)
			(end 0.7874 -0.4064)
			(stroke
				(width 0.1524)
				(type default)
			)
			(layer "F.SilkS")
		)
		(fp_line
			(start -0.7874 0.4064)
			(end -0.7874 -0.4064)
			(stroke
				(width 0.1524)
				(type default)
			)
			(layer "F.SilkS")
		)
		(fp_line
			(start 0.7874 -0.4064)
			(end 0.7874 0.4064)
			(stroke
				(width 0.1524)
				(type default)
			)
			(layer "F.SilkS")
		)
		(fp_line
			(start 0.7874 0.4064)
			(end -0.7874 0.4064)
			(stroke
				(width 0.1524)
				(type default)
			)
			(layer "F.SilkS")
		)
		(fp_poly
			(pts
				(xy -0.508 0.2794) (xy -0.508 0.2286) (xy -0.635 0.2286) (xy -0.635 -0.254) (xy -0.5334 -0.254)
				(xy -0.5334 -0.2794) (xy 0.5334 -0.2794) (xy 0.5334 -0.254) (xy 0.635 -0.254) (xy 0.635 0.254) (xy 0.5334 0.254)
				(xy 0.5334 0.2794)
			)
			(stroke
				(width 0)
				(type default)
			)
			(fill no)
			(layer "F.CrtYd")
		)
		(pad "1" smd rect
			(at 0.40005 0)
			(size 0.4572 0.508)
			(layers "F.Cu" "F.Mask" "F.Paste")
			(net "PSU1_PS_KILL")
		)
		(pad "2" smd rect
			(at -0.40005 0)
			(size 0.4572 0.508)
			(layers "F.Cu" "F.Mask" "F.Paste")
			(net "GND")
		)
	)
	(footprint ""
		(layer "F.Cu")
		(at 13.455142 -321.89166 180)
		(property "Reference" "R143"
			(at -1.706626 -0.091186 0)
			(unlocked yes)
			(layer "F.SilkS")
			(effects
				(font
					(size 0.7874 0.5842)
					(thickness 0.1524)
				)
				(justify left)
			)
		)
		(property "Value" ""
			(at 0 0 180)
			(layer "F.Fab")
			(effects
				(font
					(size 1.27 1.27)
				)
			)
		)
		(duplicate_pad_numbers_are_jumpers no)
		(fp_line
			(start 0.7874 0.4064)
			(end -0.7874 0.4064)
			(stroke
				(width 0.1524)
				(type default)
			)
			(layer "F.SilkS")
		)
		(fp_line
			(start 0.7874 -0.4064)
			(end 0.7874 0.4064)
			(stroke
				(width 0.1524)
				(type default)
			)
			(layer "F.SilkS")
		)
		(fp_line
			(start -0.7874 0.4064)
			(end -0.7874 -0.4064)
			(stroke
				(width 0.1524)
				(type default)
			)
			(layer "F.SilkS")
		)
		(fp_line
			(start -0.7874 -0.4064)
			(end 0.7874 -0.4064)
			(stroke
				(width 0.1524)
				(type default)
			)
			(layer "F.SilkS")
		)
		(fp_poly
			(pts
				(xy -0.508 0.2794) (xy -0.508 0.2286) (xy -0.635 0.2286) (xy -0.635 -0.254) (xy -0.5334 -0.254)
				(xy -0.5334 -0.2794) (xy 0.5334 -0.2794) (xy 0.5334 -0.254) (xy 0.635 -0.254) (xy 0.635 0.254) (xy 0.5334 0.254)
				(xy 0.5334 0.2794)
			)
			(stroke
				(width 0)
				(type default)
			)
			(fill no)
			(layer "F.CrtYd")
		)
		(pad "1" smd rect
			(at 0.40005 0 180)
			(size 0.4572 0.508)
			(layers "F.Cu" "F.Mask" "F.Paste")
			(net "FAN2_TACH")
		)
		(pad "2" smd rect
			(at -0.40005 0 180)
			(size 0.4572 0.508)
			(layers "F.Cu" "F.Mask" "F.Paste")
			(net "P12V")
		)
	)
	(footprint ""
		(layer "F.Cu")
		(at 25.857708 -363.01553)
		(property "Reference" "R80"
			(at -3.917442 -0.225298 0)
			(unlocked yes)
			(layer "F.SilkS")
			(effects
				(font
					(size 0.7874 0.5842)
					(thickness 0.1524)
				)
				(justify left)
			)
		)
		(property "Value" ""
			(at 0 0 0)
			(layer "F.Fab")
			(effects
				(font
					(size 1.27 1.27)
				)
			)
		)
		(duplicate_pad_numbers_are_jumpers no)
		(fp_line
			(start -0.7874 -0.4064)
			(end 0.7874 -0.4064)
			(stroke
				(width 0.1524)
				(type default)
			)
			(layer "F.SilkS")
		)
		(fp_line
			(start -0.7874 0.4064)
			(end -0.7874 -0.4064)
			(stroke
				(width 0.1524)
				(type default)
			)
			(layer "F.SilkS")
		)
		(fp_line
			(start 0.7874 -0.4064)
			(end 0.7874 0.4064)
			(stroke
				(width 0.1524)
				(type default)
			)
			(layer "F.SilkS")
		)
		(fp_line
			(start 0.7874 0.4064)
			(end -0.7874 0.4064)
			(stroke
				(width 0.1524)
				(type default)
			)
			(layer "F.SilkS")
		)
		(fp_poly
			(pts
				(xy -0.508 0.2794) (xy -0.508 0.2286) (xy -0.635 0.2286) (xy -0.635 -0.254) (xy -0.5334 -0.254)
				(xy -0.5334 -0.2794) (xy 0.5334 -0.2794) (xy 0.5334 -0.254) (xy 0.635 -0.254) (xy 0.635 0.254) (xy 0.5334 0.254)
				(xy 0.5334 0.2794)
			)
			(stroke
				(width 0)
				(type default)
			)
			(fill no)
			(layer "F.CrtYd")
		)
		(pad "1" smd rect
			(at 0.40005 0)
			(size 0.4572 0.508)
			(layers "F.Cu" "F.Mask" "F.Paste")
			(net "PSU5_RESET")
		)
		(pad "2" smd rect
			(at -0.40005 0)
			(size 0.4572 0.508)
			(layers "F.Cu" "F.Mask" "F.Paste")
			(net "P12V_STBY")
		)
	)
	(footprint ""
		(layer "F.Cu")
		(at 27.334718 -196.234304 90)
		(property "Reference" "R121"
			(at -3.838194 0.013462 90)
			(unlocked yes)
			(layer "F.SilkS")
			(effects
				(font
					(size 0.7874 0.5842)
					(thickness 0.1524)
				)
				(justify left)
			)
		)
		(property "Value" ""
			(at 0 0 90)
			(layer "F.Fab")
			(effects
				(font
					(size 1.27 1.27)
				)
			)
		)
		(duplicate_pad_numbers_are_jumpers no)
		(fp_line
			(start 0.7874 -0.4064)
			(end 0.7874 0.4064)
			(stroke
				(width 0.1524)
				(type default)
			)
			(layer "F.SilkS")
		)
		(fp_line
			(start -0.7874 -0.4064)
			(end 0.7874 -0.4064)
			(stroke
				(width 0.1524)
				(type default)
			)
			(layer "F.SilkS")
		)
		(fp_line
			(start 0.7874 0.4064)
			(end -0.7874 0.4064)
			(stroke
				(width 0.1524)
				(type default)
			)
			(layer "F.SilkS")
		)
		(fp_line
			(start -0.7874 0.4064)
			(end -0.7874 -0.4064)
			(stroke
				(width 0.1524)
				(type default)
			)
			(layer "F.SilkS")
		)
		(fp_poly
			(pts
				(xy -0.508 0.2794) (xy -0.508 0.2286) (xy -0.635 0.2286) (xy -0.635 -0.254) (xy -0.5334 -0.254)
				(xy -0.5334 -0.2794) (xy 0.5334 -0.2794) (xy 0.5334 -0.254) (xy 0.635 -0.254) (xy 0.635 0.254) (xy 0.5334 0.254)
				(xy 0.5334 0.2794)
			)
			(stroke
				(width 0)
				(type default)
			)
			(fill no)
			(layer "F.CrtYd")
		)
		(pad "1" smd rect
			(at 0.40005 0 90)
			(size 0.4572 0.508)
			(layers "F.Cu" "F.Mask" "F.Paste")
			(net "PSU3_REMOTE_N")
		)
		(pad "2" smd rect
			(at -0.40005 0 90)
			(size 0.4572 0.508)
			(layers "F.Cu" "F.Mask" "F.Paste")
			(net "PSU3_REMOTE_R2_N")
		)
	)
	(footprint ""
		(layer "F.Cu")
		(at 70.85457 -172.135546 90)
		(property "Reference" "C33"
			(at -4.154424 0.196088 90)
			(unlocked yes)
			(layer "F.SilkS")
			(effects
				(font
					(size 0.7874 0.5842)
					(thickness 0.1524)
				)
				(justify left)
			)
		)
		(property "Value" ""
			(at 0 0 90)
			(layer "F.Fab")
			(effects
				(font
					(size 1.27 1.27)
				)
			)
		)
		(duplicate_pad_numbers_are_jumpers no)
		(fp_line
			(start 0.7874 -0.4064)
			(end 0.7874 0.4064)
			(stroke
				(width 0.1524)
				(type default)
			)
			(layer "F.SilkS")
		)
		(fp_line
			(start -0.7874 -0.4064)
			(end 0.7874 -0.4064)
			(stroke
				(width 0.1524)
				(type default)
			)
			(layer "F.SilkS")
		)
		(fp_line
			(start 0 0.381)
			(end 0 -0.381)
			(stroke
				(width 0.1524)
				(type default)
			)
			(layer "F.SilkS")
		)
		(fp_line
			(start 0.7874 0.4064)
			(end -0.7874 0.4064)
			(stroke
				(width 0.1524)
				(type default)
			)
			(layer "F.SilkS")
		)
		(fp_line
			(start -0.7874 0.4064)
			(end -0.7874 -0.4064)
			(stroke
				(width 0.1524)
				(type default)
			)
			(layer "F.SilkS")
		)
		(fp_poly
			(pts
				(xy -0.5334 0.254) (xy -0.635 0.254) (xy -0.635 0.2286) (xy -0.635 -0.254) (xy -0.5334 -0.254) (xy -0.5334 -0.2794)
				(xy 0.5334 -0.2794) (xy 0.5334 -0.254) (xy 0.635 -0.254) (xy 0.635 0.254) (xy 0.5334 0.254) (xy 0.5334 0.2794)
				(xy -0.508 0.2794) (xy -0.5334 0.2794)
			)
			(stroke
				(width 0)
				(type default)
			)
			(fill no)
			(layer "F.CrtYd")
		)
		(pad "1" smd rect
			(at 0.40005 0 90)
			(size 0.4572 0.508)
			(layers "F.Cu" "F.Mask" "F.Paste")
			(net "P12V")
		)
		(pad "2" smd rect
			(at -0.40005 0 90)
			(size 0.4572 0.508)
			(layers "F.Cu" "F.Mask" "F.Paste")
			(net "GND")
		)
	)
	(footprint ""
		(layer "F.Cu")
		(at 73.199752 -285.966154 -90)
		(property "Reference" "C44"
			(at 0.870204 -4.091432 90)
			(unlocked yes)
			(layer "F.SilkS")
			(effects
				(font
					(size 0.7874 0.5842)
					(thickness 0.1524)
				)
				(justify left)
			)
		)
		(property "Value" ""
			(at 0 0 270)
			(layer "F.Fab")
			(effects
				(font
					(size 1.27 1.27)
				)
			)
		)
		(duplicate_pad_numbers_are_jumpers no)
		(fp_line
			(start -0.7874 0.4064)
			(end -0.7874 -0.4064)
			(stroke
				(width 0.1524)
				(type default)
			)
			(layer "F.SilkS")
		)
		(fp_line
			(start 0.7874 0.4064)
			(end -0.7874 0.4064)
			(stroke
				(width 0.1524)
				(type default)
			)
			(layer "F.SilkS")
		)
		(fp_line
			(start 0 0.381)
			(end 0 -0.381)
			(stroke
				(width 0.1524)
				(type default)
			)
			(layer "F.SilkS")
		)
		(fp_line
			(start -0.7874 -0.4064)
			(end 0.7874 -0.4064)
			(stroke
				(width 0.1524)
				(type default)
			)
			(layer "F.SilkS")
		)
		(fp_line
			(start 0.7874 -0.4064)
			(end 0.7874 0.4064)
			(stroke
				(width 0.1524)
				(type default)
			)
			(layer "F.SilkS")
		)
		(fp_poly
			(pts
				(xy -0.5334 0.254) (xy -0.635 0.254) (xy -0.635 0.2286) (xy -0.635 -0.254) (xy -0.5334 -0.254) (xy -0.5334 -0.2794)
				(xy 0.5334 -0.2794) (xy 0.5334 -0.254) (xy 0.635 -0.254) (xy 0.635 0.254) (xy 0.5334 0.254) (xy 0.5334 0.2794)
				(xy -0.508 0.2794) (xy -0.5334 0.2794)
			)
			(stroke
				(width 0)
				(type default)
			)
			(fill no)
			(layer "F.CrtYd")
		)
		(pad "1" smd rect
			(at 0.40005 0 270)
			(size 0.4572 0.508)
			(layers "F.Cu" "F.Mask" "F.Paste")
			(net "P12V")
		)
		(pad "2" smd rect
			(at -0.40005 0 270)
			(size 0.4572 0.508)
			(layers "F.Cu" "F.Mask" "F.Paste")
			(net "GND")
		)
	)
	(footprint ""
		(layer "F.Cu")
		(at 39.873936 -462.37144)
		(property "Reference" "R18"
			(at 1.141984 0.133096 0)
			(unlocked yes)
			(layer "F.SilkS")
			(effects
				(font
					(size 0.7874 0.5842)
					(thickness 0.1524)
				)
				(justify left)
			)
		)
		(property "Value" ""
			(at 0 0 0)
			(layer "F.Fab")
			(effects
				(font
					(size 1.27 1.27)
				)
			)
		)
		(duplicate_pad_numbers_are_jumpers no)
		(fp_line
			(start -0.7874 -0.4064)
			(end 0.7874 -0.4064)
			(stroke
				(width 0.1524)
				(type default)
			)
			(layer "F.SilkS")
		)
		(fp_line
			(start -0.7874 0.4064)
			(end -0.7874 -0.4064)
			(stroke
				(width 0.1524)
				(type default)
			)
			(layer "F.SilkS")
		)
		(fp_line
			(start 0.7874 -0.4064)
			(end 0.7874 0.4064)
			(stroke
				(width 0.1524)
				(type default)
			)
			(layer "F.SilkS")
		)
		(fp_line
			(start 0.7874 0.4064)
			(end -0.7874 0.4064)
			(stroke
				(width 0.1524)
				(type default)
			)
			(layer "F.SilkS")
		)
		(fp_poly
			(pts
				(xy -0.508 0.2794) (xy -0.508 0.2286) (xy -0.635 0.2286) (xy -0.635 -0.254) (xy -0.5334 -0.254)
				(xy -0.5334 -0.2794) (xy 0.5334 -0.2794) (xy 0.5334 -0.254) (xy 0.635 -0.254) (xy 0.635 0.254) (xy 0.5334 0.254)
				(xy 0.5334 0.2794)
			)
			(stroke
				(width 0)
				(type default)
			)
			(fill no)
			(layer "F.CrtYd")
		)
		(pad "1" smd rect
			(at 0.40005 0)
			(size 0.4572 0.508)
			(layers "F.Cu" "F.Mask" "F.Paste")
			(net "PSU6_AD0")
		)
		(pad "2" smd rect
			(at -0.40005 0)
			(size 0.4572 0.508)
			(layers "F.Cu" "F.Mask" "F.Paste")
			(net "P12V_STBY")
		)
	)
	(footprint ""
		(layer "F.Cu")
		(at 71.810118 -483.48138 90)
		(property "Reference" "C82"
			(at -4.162806 0.225044 90)
			(unlocked yes)
			(layer "F.SilkS")
			(effects
				(font
					(size 0.7874 0.5842)
					(thickness 0.1524)
				)
				(justify left)
			)
		)
		(property "Value" ""
			(at 0 0 90)
			(layer "F.Fab")
			(effects
				(font
					(size 1.27 1.27)
				)
			)
		)
		(duplicate_pad_numbers_are_jumpers no)
		(fp_line
			(start 0.7874 -0.4064)
			(end 0.7874 0.4064)
			(stroke
				(width 0.1524)
				(type default)
			)
			(layer "F.SilkS")
		)
		(fp_line
			(start -0.7874 -0.4064)
			(end 0.7874 -0.4064)
			(stroke
				(width 0.1524)
				(type default)
			)
			(layer "F.SilkS")
		)
		(fp_line
			(start 0 0.381)
			(end 0 -0.381)
			(stroke
				(width 0.1524)
				(type default)
			)
			(layer "F.SilkS")
		)
		(fp_line
			(start 0.7874 0.4064)
			(end -0.7874 0.4064)
			(stroke
				(width 0.1524)
				(type default)
			)
			(layer "F.SilkS")
		)
		(fp_line
			(start -0.7874 0.4064)
			(end -0.7874 -0.4064)
			(stroke
				(width 0.1524)
				(type default)
			)
			(layer "F.SilkS")
		)
		(fp_poly
			(pts
				(xy -0.5334 0.254) (xy -0.635 0.254) (xy -0.635 0.2286) (xy -0.635 -0.254) (xy -0.5334 -0.254) (xy -0.5334 -0.2794)
				(xy 0.5334 -0.2794) (xy 0.5334 -0.254) (xy 0.635 -0.254) (xy 0.635 0.254) (xy 0.5334 0.254) (xy 0.5334 0.2794)
				(xy -0.508 0.2794) (xy -0.5334 0.2794)
			)
			(stroke
				(width 0)
				(type default)
			)
			(fill no)
			(layer "F.CrtYd")
		)
		(pad "1" smd rect
			(at 0.40005 0 90)
			(size 0.4572 0.508)
			(layers "F.Cu" "F.Mask" "F.Paste")
			(net "P12V")
		)
		(pad "2" smd rect
			(at -0.40005 0 90)
			(size 0.4572 0.508)
			(layers "F.Cu" "F.Mask" "F.Paste")
			(net "GND")
		)
	)
	(footprint ""
		(layer "F.Cu")
		(at 76.120498 -18.749772 -90)
		(property "Reference" "C2"
			(at -1.75133 0.044704 90)
			(unlocked yes)
			(layer "F.SilkS")
			(effects
				(font
					(size 0.7874 0.5842)
					(thickness 0.1524)
				)
				(justify left)
			)
		)
		(property "Value" ""
			(at 0 0 270)
			(layer "F.Fab")
			(effects
				(font
					(size 1.27 1.27)
				)
			)
		)
		(duplicate_pad_numbers_are_jumpers no)
		(fp_line
			(start -0.7874 0.4064)
			(end -0.7874 -0.4064)
			(stroke
				(width 0.1524)
				(type default)
			)
			(layer "F.SilkS")
		)
		(fp_line
			(start 0.7874 0.4064)
			(end -0.7874 0.4064)
			(stroke
				(width 0.1524)
				(type default)
			)
			(layer "F.SilkS")
		)
		(fp_line
			(start 0 0.381)
			(end 0 -0.381)
			(stroke
				(width 0.1524)
				(type default)
			)
			(layer "F.SilkS")
		)
		(fp_line
			(start -0.7874 -0.4064)
			(end 0.7874 -0.4064)
			(stroke
				(width 0.1524)
				(type default)
			)
			(layer "F.SilkS")
		)
		(fp_line
			(start 0.7874 -0.4064)
			(end 0.7874 0.4064)
			(stroke
				(width 0.1524)
				(type default)
			)
			(layer "F.SilkS")
		)
		(fp_poly
			(pts
				(xy -0.5334 0.254) (xy -0.635 0.254) (xy -0.635 0.2286) (xy -0.635 -0.254) (xy -0.5334 -0.254) (xy -0.5334 -0.2794)
				(xy 0.5334 -0.2794) (xy 0.5334 -0.254) (xy 0.635 -0.254) (xy 0.635 0.254) (xy 0.5334 0.254) (xy 0.5334 0.2794)
				(xy -0.508 0.2794) (xy -0.5334 0.2794)
			)
			(stroke
				(width 0)
				(type default)
			)
			(fill no)
			(layer "F.CrtYd")
		)
		(pad "1" smd rect
			(at 0.40005 0 270)
			(size 0.4572 0.508)
			(layers "F.Cu" "F.Mask" "F.Paste")
			(net "P12V")
		)
		(pad "2" smd rect
			(at -0.40005 0 270)
			(size 0.4572 0.508)
			(layers "F.Cu" "F.Mask" "F.Paste")
			(net "GND")
		)
	)
	(footprint ""
		(layer "F.Cu")
		(at 40.303958 -370.099336 180)
		(property "Reference" "R24"
			(at -1.863598 -0.010922 0)
			(unlocked yes)
			(layer "F.SilkS")
			(effects
				(font
					(size 0.7874 0.5842)
					(thickness 0.1524)
				)
				(justify left)
			)
		)
		(property "Value" ""
			(at 0 0 180)
			(layer "F.Fab")
			(effects
				(font
					(size 1.27 1.27)
				)
			)
		)
		(duplicate_pad_numbers_are_jumpers no)
		(fp_line
			(start 0.7874 0.4064)
			(end -0.7874 0.4064)
			(stroke
				(width 0.1524)
				(type default)
			)
			(layer "F.SilkS")
		)
		(fp_line
			(start 0.7874 -0.4064)
			(end 0.7874 0.4064)
			(stroke
				(width 0.1524)
				(type default)
			)
			(layer "F.SilkS")
		)
		(fp_line
			(start -0.7874 0.4064)
			(end -0.7874 -0.4064)
			(stroke
				(width 0.1524)
				(type default)
			)
			(layer "F.SilkS")
		)
		(fp_line
			(start -0.7874 -0.4064)
			(end 0.7874 -0.4064)
			(stroke
				(width 0.1524)
				(type default)
			)
			(layer "F.SilkS")
		)
		(fp_poly
			(pts
				(xy -0.508 0.2794) (xy -0.508 0.2286) (xy -0.635 0.2286) (xy -0.635 -0.254) (xy -0.5334 -0.254)
				(xy -0.5334 -0.2794) (xy 0.5334 -0.2794) (xy 0.5334 -0.254) (xy 0.635 -0.254) (xy 0.635 0.254) (xy 0.5334 0.254)
				(xy 0.5334 0.2794)
			)
			(stroke
				(width 0)
				(type default)
			)
			(fill no)
			(layer "F.CrtYd")
		)
		(pad "1" smd rect
			(at 0.40005 0 180)
			(size 0.4572 0.508)
			(layers "F.Cu" "F.Mask" "F.Paste")
			(net "PSU5_RETURN")
		)
		(pad "2" smd rect
			(at -0.40005 0 180)
			(size 0.4572 0.508)
			(layers "F.Cu" "F.Mask" "F.Paste")
			(net "GND")
		)
	)
)
